(kicad_pcb
	(version 20260206)
	(generator "pcbnew")
	(generator_version "10.0")
	(general
		(thickness 1.6)
		(legacy_teardrops no)
	)
	(paper "A4")
	(title_block
		(title "04192023_DAF0TMB3IC0_F0TG_MB_C_brd_V02_OCP.brd")
		(comment 1 "Grand Teton / footprints 732-739 of 8354")
	)
	(layers
		(0 "F.Cu" signal "TOP")
		(4 "In1.Cu" signal "GND")
		(6 "In2.Cu" signal "IN1")
		(8 "In3.Cu" signal "GND1")
		(10 "In4.Cu" signal "IN2")
		(12 "In5.Cu" signal "GND2")
		(14 "In6.Cu" signal "IN3")
		(16 "In7.Cu" signal "GND3")
		(18 "In8.Cu" signal "VCC")
		(20 "In9.Cu" signal "VCC1")
		(22 "In10.Cu" signal "GND4")
		(24 "In11.Cu" signal "IN4")
		(26 "In12.Cu" signal "GND5")
		(28 "In13.Cu" signal "IN5")
		(30 "In14.Cu" signal "GND6")
		(32 "In15.Cu" signal "IN6")
		(34 "In16.Cu" signal "GND7")
		(2 "B.Cu" signal "BOTTOM")
		(9 "F.Adhes" user "F.Adhesive")
		(11 "B.Adhes" user "B.Adhesive")
		(13 "F.Paste" user "Package Geometry/Pastemask Top")
		(15 "B.Paste" user "Package Geometry/Pastemask Bottom")
		(5 "F.SilkS" user "Ref Des/Silkscreen Top")
		(7 "B.SilkS" user "Ref Des/Silkscreen Bottom")
		(1 "F.Mask" user "Board Geometry/Soldermask Top")
		(3 "B.Mask" user "Board Geometry/Soldermask Bottom")
		(17 "Dwgs.User" user "User.Drawings")
		(19 "Cmts.User" user "User.Comments")
		(21 "Eco1.User" user "User.Eco1")
		(23 "Eco2.User" user "User.Eco2")
		(25 "Edge.Cuts" user "Board Geometry/Outline")
		(27 "Margin" user)
		(31 "F.CrtYd" user "Package Geometry/Place Bound Top")
		(29 "B.CrtYd" user "Package Geometry/Place Bound Bottom")
		(35 "F.Fab" user "Ref Des/Assembly Top")
		(33 "B.Fab" user "Ref Des/Assembly Bottom")
	)
	(footprint ""
		(layer "F.Cu")
		(at 285.75254 -403.961092 -90)
		(property "Reference" "R2625"
			(at 0 0 270)
			(layer "F.SilkS")
			(hide yes)
			(effects
				(font
					(size 1.27 1.27)
				)
			)
		)
		(property "Value" ""
			(at 0 0 270)
			(layer "F.Fab")
			(effects
				(font
					(size 1.27 1.27)
				)
			)
		)
		(duplicate_pad_numbers_are_jumpers no)
		(fp_line
			(start -0.7874 0.4064)
			(end -0.7874 -0.4064)
			(stroke
				(width 0.1524)
				(type default)
			)
			(layer "F.SilkS")
		)
		(fp_line
			(start 0.7874 0.4064)
			(end -0.7874 0.4064)
			(stroke
				(width 0.1524)
				(type default)
			)
			(layer "F.SilkS")
		)
		(fp_line
			(start -0.7874 -0.4064)
			(end 0.7874 -0.4064)
			(stroke
				(width 0.1524)
				(type default)
			)
			(layer "F.SilkS")
		)
		(fp_line
			(start 0.7874 -0.4064)
			(end 0.7874 0.4064)
			(stroke
				(width 0.1524)
				(type default)
			)
			(layer "F.SilkS")
		)
		(fp_line
			(start -0.67945 0.3048)
			(end -0.67945 -0.305054)
			(stroke
				(width 0.1)
				(type default)
			)
			(layer "F.Fab")
		)
		(fp_line
			(start -0.12065 0.3048)
			(end -0.67945 0.3048)
			(stroke
				(width 0.1)
				(type default)
			)
			(layer "F.Fab")
		)
		(fp_line
			(start 0.120396 0.3048)
			(end 0.120396 0.2794)
			(stroke
				(width 0.1)
				(type default)
			)
			(layer "F.Fab")
		)
		(fp_line
			(start 0.67945 0.3048)
			(end 0.120396 0.3048)
			(stroke
				(width 0.1)
				(type default)
			)
			(layer "F.Fab")
		)
		(fp_line
			(start -0.12065 0.2794)
			(end -0.12065 0.3048)
			(stroke
				(width 0.1)
				(type default)
			)
			(layer "F.Fab")
		)
		(fp_line
			(start 0.120396 0.2794)
			(end -0.12065 0.2794)
			(stroke
				(width 0.1)
				(type default)
			)
			(layer "F.Fab")
		)
		(fp_line
			(start -0.12065 -0.2794)
			(end 0.12065 -0.2794)
			(stroke
				(width 0.1)
				(type default)
			)
			(layer "F.Fab")
		)
		(fp_line
			(start 0.12065 -0.2794)
			(end 0.12065 -0.3048)
			(stroke
				(width 0.1)
				(type default)
			)
			(layer "F.Fab")
		)
		(fp_line
			(start 0.12065 -0.3048)
			(end 0.67945 -0.3048)
			(stroke
				(width 0.1)
				(type default)
			)
			(layer "F.Fab")
		)
		(fp_line
			(start 0.67945 -0.3048)
			(end 0.67945 0.3048)
			(stroke
				(width 0.1)
				(type default)
			)
			(layer "F.Fab")
		)
		(fp_line
			(start -0.67945 -0.305054)
			(end -0.12065 -0.305054)
			(stroke
				(width 0.1)
				(type default)
			)
			(layer "F.Fab")
		)
		(fp_line
			(start -0.12065 -0.305054)
			(end -0.12065 -0.2794)
			(stroke
				(width 0.1)
				(type default)
			)
			(layer "F.Fab")
		)
		(pad "1" smd circle
			(at -0.40005 0 270)
			(size 0 0)
			(layers "F.Cu" "F.Mask" "F.Paste")
			(net "P12V_HSC_TEMP_R")
		)
		(pad "2" smd circle
			(at 0.40005 0 270)
			(size 0 0)
			(layers "F.Cu" "F.Mask" "F.Paste")
			(net "P12V_HSC_TEMP_D+")
		)
	)
	(footprint ""
		(layer "F.Cu")
		(at 181.388766 -169.117518 -90)
		(property "Reference" "R1336"
			(at 0 0 270)
			(layer "F.SilkS")
			(hide yes)
			(effects
				(font
					(size 1.27 1.27)
				)
			)
		)
		(property "Value" ""
			(at 0 0 270)
			(layer "F.Fab")
			(effects
				(font
					(size 1.27 1.27)
				)
			)
		)
		(duplicate_pad_numbers_are_jumpers no)
		(fp_line
			(start -0.7874 0.4064)
			(end -0.7874 -0.4064)
			(stroke
				(width 0.1524)
				(type default)
			)
			(layer "F.SilkS")
		)
		(fp_line
			(start 0.7874 0.4064)
			(end -0.7874 0.4064)
			(stroke
				(width 0.1524)
				(type default)
			)
			(layer "F.SilkS")
		)
		(fp_line
			(start -0.7874 -0.4064)
			(end 0.7874 -0.4064)
			(stroke
				(width 0.1524)
				(type default)
			)
			(layer "F.SilkS")
		)
		(fp_line
			(start 0.7874 -0.4064)
			(end 0.7874 0.4064)
			(stroke
				(width 0.1524)
				(type default)
			)
			(layer "F.SilkS")
		)
		(fp_line
			(start -0.67945 0.3048)
			(end -0.67945 -0.305054)
			(stroke
				(width 0.1)
				(type default)
			)
			(layer "F.Fab")
		)
		(fp_line
			(start -0.12065 0.3048)
			(end -0.67945 0.3048)
			(stroke
				(width 0.1)
				(type default)
			)
			(layer "F.Fab")
		)
		(fp_line
			(start 0.120396 0.3048)
			(end 0.120396 0.2794)
			(stroke
				(width 0.1)
				(type default)
			)
			(layer "F.Fab")
		)
		(fp_line
			(start 0.67945 0.3048)
			(end 0.120396 0.3048)
			(stroke
				(width 0.1)
				(type default)
			)
			(layer "F.Fab")
		)
		(fp_line
			(start -0.12065 0.2794)
			(end -0.12065 0.3048)
			(stroke
				(width 0.1)
				(type default)
			)
			(layer "F.Fab")
		)
		(fp_line
			(start 0.120396 0.2794)
			(end -0.12065 0.2794)
			(stroke
				(width 0.1)
				(type default)
			)
			(layer "F.Fab")
		)
		(fp_line
			(start -0.12065 -0.2794)
			(end 0.12065 -0.2794)
			(stroke
				(width 0.1)
				(type default)
			)
			(layer "F.Fab")
		)
		(fp_line
			(start 0.12065 -0.2794)
			(end 0.12065 -0.3048)
			(stroke
				(width 0.1)
				(type default)
			)
			(layer "F.Fab")
		)
		(fp_line
			(start 0.12065 -0.3048)
			(end 0.67945 -0.3048)
			(stroke
				(width 0.1)
				(type default)
			)
			(layer "F.Fab")
		)
		(fp_line
			(start 0.67945 -0.3048)
			(end 0.67945 0.3048)
			(stroke
				(width 0.1)
				(type default)
			)
			(layer "F.Fab")
		)
		(fp_line
			(start -0.67945 -0.305054)
			(end -0.12065 -0.305054)
			(stroke
				(width 0.1)
				(type default)
			)
			(layer "F.Fab")
		)
		(fp_line
			(start -0.12065 -0.305054)
			(end -0.12065 -0.2794)
			(stroke
				(width 0.1)
				(type default)
			)
			(layer "F.Fab")
		)
		(pad "1" smd rect
			(at -0.40005 0 90)
			(size 0.4572 0.508)
			(layers "F.Cu" "F.Mask" "F.Paste")
			(net "I3C_SPD_DDRGL_CPU1_BYPASS_SCL")
		)
		(pad "2" smd rect
			(at 0.40005 0 90)
			(size 0.4572 0.508)
			(layers "F.Cu" "F.Mask" "F.Paste")
			(net "I3C_SPD_DDRGL_CPU1_SCL")
		)
	)
	(footprint ""
		(layer "F.Cu")
		(at 70.9676 -381.7874)
		(property "Reference" "R1387"
			(at 0 0 0)
			(layer "F.SilkS")
			(hide yes)
			(effects
				(font
					(size 1.27 1.27)
				)
			)
		)
		(property "Value" ""
			(at 0 0 0)
			(layer "F.Fab")
			(effects
				(font
					(size 1.27 1.27)
				)
			)
		)
		(duplicate_pad_numbers_are_jumpers no)
		(fp_line
			(start -0.32512 -0.175006)
			(end 0.32512 -0.175006)
			(stroke
				(width 0.1)
				(type default)
			)
			(layer "F.Fab")
		)
		(fp_line
			(start -0.32512 0.175006)
			(end -0.32512 -0.175006)
			(stroke
				(width 0.1)
				(type default)
			)
			(layer "F.Fab")
		)
		(fp_line
			(start 0.32512 -0.175006)
			(end 0.32512 0.175006)
			(stroke
				(width 0.1)
				(type default)
			)
			(layer "F.Fab")
		)
		(fp_line
			(start 0.32512 0.175006)
			(end -0.32512 0.175006)
			(stroke
				(width 0.1)
				(type default)
			)
			(layer "F.Fab")
		)
		(pad "1" smd rect
			(at -0.2667 0)
			(size 0.3048 0.381)
			(layers "F.Cu" "F.Mask" "F.Paste")
			(net "CLKREQ_RT_CPU1_P0_N")
		)
		(pad "2" smd rect
			(at 0.2667 0 180)
			(size 0.3048 0.381)
			(layers "F.Cu" "F.Mask" "F.Paste")
			(net "GND")
		)
	)
	(footprint ""
		(layer "F.Cu")
		(at 399.303748 -17.624298 90)
		(property "Reference" "C1555"
			(at 0 0 90)
			(layer "F.SilkS")
			(hide yes)
			(effects
				(font
					(size 1.27 1.27)
				)
			)
		)
		(property "Value" ""
			(at 0 0 90)
			(layer "F.Fab")
			(effects
				(font
					(size 1.27 1.27)
				)
			)
		)
		(duplicate_pad_numbers_are_jumpers no)
		(fp_line
			(start 0.299974 -0.150114)
			(end 0.299974 0.150114)
			(stroke
				(width 0.1)
				(type default)
			)
			(layer "F.Fab")
		)
		(fp_line
			(start -0.299974 -0.150114)
			(end 0.299974 -0.150114)
			(stroke
				(width 0.1)
				(type default)
			)
			(layer "F.Fab")
		)
		(fp_line
			(start 0.299974 0.150114)
			(end -0.299974 0.150114)
			(stroke
				(width 0.1)
				(type default)
			)
			(layer "F.Fab")
		)
		(fp_line
			(start -0.299974 0.150114)
			(end -0.299974 -0.150114)
			(stroke
				(width 0.1)
				(type default)
			)
			(layer "F.Fab")
		)
		(pad "1" smd rect
			(at -0.2667 0 90)
			(size 0.3048 0.381)
			(layers "F.Cu" "F.Mask" "F.Paste")
			(net "P5E_CPU0_G3_TX_C_DP<12>")
		)
		(pad "2" smd rect
			(at 0.2667 0 90)
			(size 0.3048 0.381)
			(layers "F.Cu" "F.Mask" "F.Paste")
			(net "P5E_CPU0_G3_TX_DP<12>")
		)
	)
	(footprint ""
		(layer "F.Cu")
		(at 85.978492 -185.748168)
		(property "Reference" "PC170"
			(at 0 0 0)
			(layer "F.SilkS")
			(hide yes)
			(effects
				(font
					(size 1.27 1.27)
				)
			)
		)
		(property "Value" ""
			(at 0 0 0)
			(layer "F.Fab")
			(effects
				(font
					(size 1.27 1.27)
				)
			)
		)
		(duplicate_pad_numbers_are_jumpers no)
		(fp_line
			(start -0.7874 -0.4064)
			(end 0.7874 -0.4064)
			(stroke
				(width 0.1524)
				(type default)
			)
			(layer "F.SilkS")
		)
		(fp_line
			(start -0.7874 0.4064)
			(end -0.7874 -0.4064)
			(stroke
				(width 0.1524)
				(type default)
			)
			(layer "F.SilkS")
		)
		(fp_line
			(start 0.7874 -0.4064)
			(end 0.7874 0.4064)
			(stroke
				(width 0.1524)
				(type default)
			)
			(layer "F.SilkS")
		)
		(fp_line
			(start 0.7874 0.4064)
			(end -0.7874 0.4064)
			(stroke
				(width 0.1524)
				(type default)
			)
			(layer "F.SilkS")
		)
		(fp_line
			(start -0.67945 -0.305054)
			(end -0.12065 -0.305054)
			(stroke
				(width 0.1)
				(type default)
			)
			(layer "F.Fab")
		)
		(fp_line
			(start -0.67945 0.3048)
			(end -0.67945 -0.305054)
			(stroke
				(width 0.1)
				(type default)
			)
			(layer "F.Fab")
		)
		(fp_line
			(start -0.12065 -0.305054)
			(end -0.12065 -0.2794)
			(stroke
				(width 0.1)
				(type default)
			)
			(layer "F.Fab")
		)
		(fp_line
			(start -0.12065 -0.2794)
			(end 0.12065 -0.2794)
			(stroke
				(width 0.1)
				(type default)
			)
			(layer "F.Fab")
		)
		(fp_line
			(start -0.12065 0.2794)
			(end -0.12065 0.3048)
			(stroke
				(width 0.1)
				(type default)
			)
			(layer "F.Fab")
		)
		(fp_line
			(start -0.12065 0.3048)
			(end -0.67945 0.3048)
			(stroke
				(width 0.1)
				(type default)
			)
			(layer "F.Fab")
		)
		(fp_line
			(start 0.120396 0.2794)
			(end -0.12065 0.2794)
			(stroke
				(width 0.1)
				(type default)
			)
			(layer "F.Fab")
		)
		(fp_line
			(start 0.120396 0.3048)
			(end 0.120396 0.2794)
			(stroke
				(width 0.1)
				(type default)
			)
			(layer "F.Fab")
		)
		(fp_line
			(start 0.12065 -0.3048)
			(end 0.67945 -0.3048)
			(stroke
				(width 0.1)
				(type default)
			)
			(layer "F.Fab")
		)
		(fp_line
			(start 0.12065 -0.2794)
			(end 0.12065 -0.3048)
			(stroke
				(width 0.1)
				(type default)
			)
			(layer "F.Fab")
		)
		(fp_line
			(start 0.67945 -0.3048)
			(end 0.67945 0.3048)
			(stroke
				(width 0.1)
				(type default)
			)
			(layer "F.Fab")
		)
		(fp_line
			(start 0.67945 0.3048)
			(end 0.120396 0.3048)
			(stroke
				(width 0.1)
				(type default)
			)
			(layer "F.Fab")
		)
		(pad "1" smd circle
			(at -0.40005 0)
			(size 0 0)
			(layers "F.Cu" "F.Mask" "F.Paste")
			(net "SW_PVDDCR_CPU0_P1_SW1")
		)
		(pad "2" smd circle
			(at 0.40005 0)
			(size 0 0)
			(layers "F.Cu" "F.Mask" "F.Paste")
			(net "SW_PVDDCR_CPU0_P1_SW1_RC")
		)
	)
	(footprint ""
		(layer "F.Cu")
		(at 24.765 -362.204 180)
		(property "Reference" "C8362"
			(at 0 0 180)
			(layer "F.SilkS")
			(hide yes)
			(effects
				(font
					(size 1.27 1.27)
				)
			)
		)
		(property "Value" ""
			(at 0 0 180)
			(layer "F.Fab")
			(effects
				(font
					(size 1.27 1.27)
				)
			)
		)
		(duplicate_pad_numbers_are_jumpers no)
		(fp_line
			(start 0.7874 0.4064)
			(end -0.7874 0.4064)
			(stroke
				(width 0.1524)
				(type default)
			)
			(layer "F.SilkS")
		)
		(fp_line
			(start 0.7874 -0.4064)
			(end 0.7874 0.4064)
			(stroke
				(width 0.1524)
				(type default)
			)
			(layer "F.SilkS")
		)
		(fp_line
			(start -0.7874 0.4064)
			(end -0.7874 -0.4064)
			(stroke
				(width 0.1524)
				(type default)
			)
			(layer "F.SilkS")
		)
		(fp_line
			(start -0.7874 -0.4064)
			(end 0.7874 -0.4064)
			(stroke
				(width 0.1524)
				(type default)
			)
			(layer "F.SilkS")
		)
		(fp_line
			(start 0.67945 0.3048)
			(end 0.120396 0.3048)
			(stroke
				(width 0.1)
				(type default)
			)
			(layer "F.Fab")
		)
		(fp_line
			(start 0.67945 -0.3048)
			(end 0.67945 0.3048)
			(stroke
				(width 0.1)
				(type default)
			)
			(layer "F.Fab")
		)
		(fp_line
			(start 0.12065 -0.2794)
			(end 0.12065 -0.3048)
			(stroke
				(width 0.1)
				(type default)
			)
			(layer "F.Fab")
		)
		(fp_line
			(start 0.12065 -0.3048)
			(end 0.67945 -0.3048)
			(stroke
				(width 0.1)
				(type default)
			)
			(layer "F.Fab")
		)
		(fp_line
			(start 0.120396 0.3048)
			(end 0.120396 0.2794)
			(stroke
				(width 0.1)
				(type default)
			)
			(layer "F.Fab")
		)
		(fp_line
			(start 0.120396 0.2794)
			(end -0.12065 0.2794)
			(stroke
				(width 0.1)
				(type default)
			)
			(layer "F.Fab")
		)
		(fp_line
			(start -0.12065 0.3048)
			(end -0.67945 0.3048)
			(stroke
				(width 0.1)
				(type default)
			)
			(layer "F.Fab")
		)
		(fp_line
			(start -0.12065 0.2794)
			(end -0.12065 0.3048)
			(stroke
				(width 0.1)
				(type default)
			)
			(layer "F.Fab")
		)
		(fp_line
			(start -0.12065 -0.2794)
			(end 0.12065 -0.2794)
			(stroke
				(width 0.1)
				(type default)
			)
			(layer "F.Fab")
		)
		(fp_line
			(start -0.12065 -0.305054)
			(end -0.12065 -0.2794)
			(stroke
				(width 0.1)
				(type default)
			)
			(layer "F.Fab")
		)
		(fp_line
			(start -0.67945 0.3048)
			(end -0.67945 -0.305054)
			(stroke
				(width 0.1)
				(type default)
			)
			(layer "F.Fab")
		)
		(fp_line
			(start -0.67945 -0.305054)
			(end -0.12065 -0.305054)
			(stroke
				(width 0.1)
				(type default)
			)
			(layer "F.Fab")
		)
		(pad "1" smd circle
			(at -0.40005 0 180)
			(size 0 0)
			(layers "F.Cu" "F.Mask" "F.Paste")
			(net "PWRGD_PVDDIO_P1_R")
		)
		(pad "2" smd circle
			(at 0.40005 0 180)
			(size 0 0)
			(layers "F.Cu" "F.Mask" "F.Paste")
			(net "GND")
		)
	)
	(footprint ""
		(layer "F.Cu")
		(at 94.605602 -40.139112)
		(property "Reference" "R3184"
			(at 0 0 0)
			(layer "F.SilkS")
			(hide yes)
			(effects
				(font
					(size 1.27 1.27)
				)
			)
		)
		(property "Value" ""
			(at 0 0 0)
			(layer "F.Fab")
			(effects
				(font
					(size 1.27 1.27)
				)
			)
		)
		(duplicate_pad_numbers_are_jumpers no)
		(fp_line
			(start -0.7874 -0.4064)
			(end 0.7874 -0.4064)
			(stroke
				(width 0.1524)
				(type default)
			)
			(layer "F.SilkS")
		)
		(fp_line
			(start -0.7874 0.4064)
			(end -0.7874 -0.4064)
			(stroke
				(width 0.1524)
				(type default)
			)
			(layer "F.SilkS")
		)
		(fp_line
			(start 0.7874 -0.4064)
			(end 0.7874 0.4064)
			(stroke
				(width 0.1524)
				(type default)
			)
			(layer "F.SilkS")
		)
		(fp_line
			(start 0.7874 0.4064)
			(end -0.7874 0.4064)
			(stroke
				(width 0.1524)
				(type default)
			)
			(layer "F.SilkS")
		)
		(fp_line
			(start -0.67945 -0.305054)
			(end -0.12065 -0.305054)
			(stroke
				(width 0.1)
				(type default)
			)
			(layer "F.Fab")
		)
		(fp_line
			(start -0.67945 0.3048)
			(end -0.67945 -0.305054)
			(stroke
				(width 0.1)
				(type default)
			)
			(layer "F.Fab")
		)
		(fp_line
			(start -0.12065 -0.305054)
			(end -0.12065 -0.2794)
			(stroke
				(width 0.1)
				(type default)
			)
			(layer "F.Fab")
		)
		(fp_line
			(start -0.12065 -0.2794)
			(end 0.12065 -0.2794)
			(stroke
				(width 0.1)
				(type default)
			)
			(layer "F.Fab")
		)
		(fp_line
			(start -0.12065 0.2794)
			(end -0.12065 0.3048)
			(stroke
				(width 0.1)
				(type default)
			)
			(layer "F.Fab")
		)
		(fp_line
			(start -0.12065 0.3048)
			(end -0.67945 0.3048)
			(stroke
				(width 0.1)
				(type default)
			)
			(layer "F.Fab")
		)
		(fp_line
			(start 0.120396 0.2794)
			(end -0.12065 0.2794)
			(stroke
				(width 0.1)
				(type default)
			)
			(layer "F.Fab")
		)
		(fp_line
			(start 0.120396 0.3048)
			(end 0.120396 0.2794)
			(stroke
				(width 0.1)
				(type default)
			)
			(layer "F.Fab")
		)
		(fp_line
			(start 0.12065 -0.3048)
			(end 0.67945 -0.3048)
			(stroke
				(width 0.1)
				(type default)
			)
			(layer "F.Fab")
		)
		(fp_line
			(start 0.12065 -0.2794)
			(end 0.12065 -0.3048)
			(stroke
				(width 0.1)
				(type default)
			)
			(layer "F.Fab")
		)
		(fp_line
			(start 0.67945 -0.3048)
			(end 0.67945 0.3048)
			(stroke
				(width 0.1)
				(type default)
			)
			(layer "F.Fab")
		)
		(fp_line
			(start 0.67945 0.3048)
			(end 0.120396 0.3048)
			(stroke
				(width 0.1)
				(type default)
			)
			(layer "F.Fab")
		)
		(pad "1" smd circle
			(at -0.40005 0)
			(size 0 0)
			(layers "F.Cu" "F.Mask" "F.Paste")
			(net "P3V3_AUX")
		)
		(pad "2" smd circle
			(at 0.40005 0)
			(size 0 0)
			(layers "F.Cu" "F.Mask" "F.Paste")
			(net "OCP_V3_2_WAKE_BUFF_N")
		)
	)
	(footprint ""
		(layer "F.Cu")
		(at 340.940644 -378.95403 -90)
		(property "Reference" "C952"
			(at 0 0 270)
			(layer "F.SilkS")
			(hide yes)
			(effects
				(font
					(size 1.27 1.27)
				)
			)
		)
		(property "Value" ""
			(at 0 0 270)
			(layer "F.Fab")
			(effects
				(font
					(size 1.27 1.27)
				)
			)
		)
		(duplicate_pad_numbers_are_jumpers no)
		(fp_line
			(start -0.299974 0.150114)
			(end -0.299974 -0.150114)
			(stroke
				(width 0.1)
				(type default)
			)
			(layer "F.Fab")
		)
		(fp_line
			(start 0.299974 0.150114)
			(end -0.299974 0.150114)
			(stroke
				(width 0.1)
				(type default)
			)
			(layer "F.Fab")
		)
		(fp_line
			(start -0.299974 -0.150114)
			(end 0.299974 -0.150114)
			(stroke
				(width 0.1)
				(type default)
			)
			(layer "F.Fab")
		)
		(fp_line
			(start 0.299974 -0.150114)
			(end 0.299974 0.150114)
			(stroke
				(width 0.1)
				(type default)
			)
			(layer "F.Fab")
		)
		(pad "1" smd rect
			(at -0.2667 0 270)
			(size 0.3048 0.381)
			(layers "F.Cu" "F.Mask" "F.Paste")
			(net "P5E_CPU0_P1_TX_C_DN<6>")
		)
		(pad "2" smd rect
			(at 0.2667 0 270)
			(size 0.3048 0.381)
			(layers "F.Cu" "F.Mask" "F.Paste")
			(net "P5E_CPU0_P1_TX_DN<6>")
		)
	)
)
